# S9S_MB_2U (Grand Teton) — schematic netlist excerpt (pin names and nets, part order shuffled) for the footprints in the layout excerpt that follows; sources: Cadence DE-HDL packaged netlist, KiCad conversion of 03242023_DA0F0TMBIJ0_F0T_Motherboard_J_brd_V01_OCP.brd

C698  Q_CAP_DIFFBUS  DIFF BUS_0.22UF 6.3V 20% X6S  pkg C0201  page 177 : \1\ = P5E_CPU1_PE4_TX_C_DN<5> ; \2\ = P5E_CPU1_PE4_TX_DN<5>
PR3844  Q_RES  71.5K 1% EMPTY  pkg 0402LF  page 157 : A = P3V3_OCP_MODE_1 ; B = GND
C935  Q_CAP_DIFFBUS  DIFF BUS_0.22UF 6.3V 20% X6S  pkg C0201  page 173 : \1\ = P5E_CPU0_PE2_TX_C_DP<15> ; \2\ = P5E_CPU0_PE2_TX_DP<15>

(kicad_pcb
	(version 20260206)
	(generator "pcbnew")
	(generator_version "10.0")
	(general
		(thickness 1.6)
		(legacy_teardrops no)
	)
	(paper "A4")
	(title_block
		(title "03242023_DA0F0TMBIJ0_F0T_Motherboard_J_brd_V01_OCP.brd")
		(comment 1 "Grand Teton / footprints 2867-2869 of 6105")
	)
	(layers
		(0 "F.Cu" signal "TOP")
		(4 "In1.Cu" signal "GND")
		(6 "In2.Cu" signal "IN1")
		(8 "In3.Cu" signal "GND1")
		(10 "In4.Cu" signal "IN2")
		(12 "In5.Cu" signal "GND2")
		(14 "In6.Cu" signal "IN3")
		(16 "In7.Cu" signal "GND3")
		(18 "In8.Cu" signal "VCC")
		(20 "In9.Cu" signal "VCC1")
		(22 "In10.Cu" signal "GND4")
		(24 "In11.Cu" signal "IN4")
		(26 "In12.Cu" signal "GND5")
		(28 "In13.Cu" signal "IN5")
		(30 "In14.Cu" signal "GND6")
		(32 "In15.Cu" signal "IN6")
		(34 "In16.Cu" signal "GND7")
		(2 "B.Cu" signal "BOTTOM")
		(9 "F.Adhes" user "F.Adhesive")
		(11 "B.Adhes" user "B.Adhesive")
		(13 "F.Paste" user "Package Geometry/Pastemask Top")
		(15 "B.Paste" user "Package Geometry/Pastemask Bottom")
		(5 "F.SilkS" user "Ref Des/Silkscreen Top")
		(7 "B.SilkS" user "Ref Des/Silkscreen Bottom")
		(1 "F.Mask" user "Board Geometry/Soldermask Top")
		(3 "B.Mask" user "Board Geometry/Soldermask Bottom")
		(17 "Dwgs.User" user "User.Drawings")
		(19 "Cmts.User" user "User.Comments")
		(21 "Eco1.User" user "User.Eco1")
		(23 "Eco2.User" user "User.Eco2")
		(25 "Edge.Cuts" user "Board Geometry/Outline")
		(27 "Margin" user)
		(31 "F.CrtYd" user "Package Geometry/Place Bound Top")
		(29 "B.CrtYd" user "Package Geometry/Place Bound Bottom")
		(35 "F.Fab" user "Ref Des/Assembly Top")
		(33 "B.Fab" user "Ref Des/Assembly Bottom")
	)
	(footprint ""
		(layer "F.Cu")
		(at 422.55694 -101.270308 -90)
		(property "Reference" "PR3844"
			(at 0 0 270)
			(layer "F.SilkS")
			(hide yes)
			(effects
				(font
					(size 1.27 1.27)
				)
			)
		)
		(property "Value" ""
			(at 0 0 270)
			(layer "F.Fab")
			(effects
				(font
					(size 1.27 1.27)
				)
			)
		)
		(duplicate_pad_numbers_are_jumpers no)
		(fp_line
			(start -0.7874 0.4064)
			(end -0.7874 -0.4064)
			(stroke
				(width 0.1524)
				(type default)
			)
			(layer "F.SilkS")
		)
		(fp_line
			(start 0.7874 0.4064)
			(end -0.7874 0.4064)
			(stroke
				(width 0.1524)
				(type default)
			)
			(layer "F.SilkS")
		)
		(fp_line
			(start -0.7874 -0.4064)
			(end 0.7874 -0.4064)
			(stroke
				(width 0.1524)
				(type default)
			)
			(layer "F.SilkS")
		)
		(fp_line
			(start 0.7874 -0.4064)
			(end 0.7874 0.4064)
			(stroke
				(width 0.1524)
				(type default)
			)
			(layer "F.SilkS")
		)
		(fp_line
			(start -0.67945 0.3048)
			(end -0.67945 -0.305054)
			(stroke
				(width 0.1)
				(type default)
			)
			(layer "F.Fab")
		)
		(fp_line
			(start -0.12065 0.3048)
			(end -0.67945 0.3048)
			(stroke
				(width 0.1)
				(type default)
			)
			(layer "F.Fab")
		)
		(fp_line
			(start 0.120396 0.3048)
			(end 0.120396 0.2794)
			(stroke
				(width 0.1)
				(type default)
			)
			(layer "F.Fab")
		)
		(fp_line
			(start 0.67945 0.3048)
			(end 0.120396 0.3048)
			(stroke
				(width 0.1)
				(type default)
			)
			(layer "F.Fab")
		)
		(fp_line
			(start -0.12065 0.2794)
			(end -0.12065 0.3048)
			(stroke
				(width 0.1)
				(type default)
			)
			(layer "F.Fab")
		)
		(fp_line
			(start 0.120396 0.2794)
			(end -0.12065 0.2794)
			(stroke
				(width 0.1)
				(type default)
			)
			(layer "F.Fab")
		)
		(fp_line
			(start -0.12065 -0.2794)
			(end 0.12065 -0.2794)
			(stroke
				(width 0.1)
				(type default)
			)
			(layer "F.Fab")
		)
		(fp_line
			(start 0.12065 -0.2794)
			(end 0.12065 -0.3048)
			(stroke
				(width 0.1)
				(type default)
			)
			(layer "F.Fab")
		)
		(fp_line
			(start 0.12065 -0.3048)
			(end 0.67945 -0.3048)
			(stroke
				(width 0.1)
				(type default)
			)
			(layer "F.Fab")
		)
		(fp_line
			(start 0.67945 -0.3048)
			(end 0.67945 0.3048)
			(stroke
				(width 0.1)
				(type default)
			)
			(layer "F.Fab")
		)
		(fp_line
			(start -0.67945 -0.305054)
			(end -0.12065 -0.305054)
			(stroke
				(width 0.1)
				(type default)
			)
			(layer "F.Fab")
		)
		(fp_line
			(start -0.12065 -0.305054)
			(end -0.12065 -0.2794)
			(stroke
				(width 0.1)
				(type default)
			)
			(layer "F.Fab")
		)
		(pad "1" smd circle
			(at -0.40005 0 270)
			(size 0 0)
			(layers "F.Cu" "F.Mask" "F.Paste")
			(net "P3V3_OCP_MODE_1")
		)
		(pad "2" smd circle
			(at 0.40005 0 270)
			(size 0 0)
			(layers "F.Cu" "F.Mask" "F.Paste")
			(net "GND")
		)
	)
	(footprint ""
		(layer "F.Cu")
		(at 372.31193 -402.371052 -90)
		(property "Reference" "C935"
			(at 0 0 270)
			(layer "F.SilkS")
			(hide yes)
			(effects
				(font
					(size 1.27 1.27)
				)
			)
		)
		(property "Value" ""
			(at 0 0 270)
			(layer "F.Fab")
			(effects
				(font
					(size 1.27 1.27)
				)
			)
		)
		(duplicate_pad_numbers_are_jumpers no)
		(fp_line
			(start -0.299974 0.150114)
			(end -0.299974 -0.150114)
			(stroke
				(width 0.1)
				(type default)
			)
			(layer "F.Fab")
		)
		(fp_line
			(start 0.299974 0.150114)
			(end -0.299974 0.150114)
			(stroke
				(width 0.1)
				(type default)
			)
			(layer "F.Fab")
		)
		(fp_line
			(start -0.299974 -0.150114)
			(end 0.299974 -0.150114)
			(stroke
				(width 0.1)
				(type default)
			)
			(layer "F.Fab")
		)
		(fp_line
			(start 0.299974 -0.150114)
			(end 0.299974 0.150114)
			(stroke
				(width 0.1)
				(type default)
			)
			(layer "F.Fab")
		)
		(pad "1" smd rect
			(at -0.2667 0 270)
			(size 0.3048 0.381)
			(layers "F.Cu" "F.Mask" "F.Paste")
			(net "P5E_CPU0_PE2_TX_C_DP<15>")
		)
		(pad "2" smd rect
			(at 0.2667 0 270)
			(size 0.3048 0.381)
			(layers "F.Cu" "F.Mask" "F.Paste")
			(net "P5E_CPU0_PE2_TX_DP<15>")
		)
	)
	(footprint ""
		(layer "F.Cu")
		(at 64.616838 -408.517344 -90)
		(property "Reference" "C698"
			(at 0 0 270)
			(layer "F.SilkS")
			(hide yes)
			(effects
				(font
					(size 1.27 1.27)
				)
			)
		)
		(property "Value" ""
			(at 0 0 270)
			(layer "F.Fab")
			(effects
				(font
					(size 1.27 1.27)
				)
			)
		)
		(duplicate_pad_numbers_are_jumpers no)
		(fp_line
			(start -0.299974 0.150114)
			(end -0.299974 -0.150114)
			(stroke
				(width 0.1)
				(type default)
			)
			(layer "F.Fab")
		)
		(fp_line
			(start 0.299974 0.150114)
			(end -0.299974 0.150114)
			(stroke
				(width 0.1)
				(type default)
			)
			(layer "F.Fab")
		)
		(fp_line
			(start -0.299974 -0.150114)
			(end 0.299974 -0.150114)
			(stroke
				(width 0.1)
				(type default)
			)
			(layer "F.Fab")
		)
		(fp_line
			(start 0.299974 -0.150114)
			(end 0.299974 0.150114)
			(stroke
				(width 0.1)
				(type default)
			)
			(layer "F.Fab")
		)
		(pad "1" smd rect
			(at -0.2667 0 270)
			(size 0.3048 0.381)
			(layers "F.Cu" "F.Mask" "F.Paste")
			(net "P5E_CPU1_PE4_TX_C_DN<5>")
		)
		(pad "2" smd rect
			(at 0.2667 0 270)
			(size 0.3048 0.381)
			(layers "F.Cu" "F.Mask" "F.Paste")
			(net "P5E_CPU1_PE4_TX_DN<5>")
		)
	)
)
